(kicad_pcb
	(version 20260206)
	(generator "pcbnew")
	(generator_version "10.0")
	(general
		(thickness 1.6)
		(legacy_teardrops no)
	)
	(paper "A4")
	(title_block
		(title "04192023_DAF0TMB3IC0_F0TG_MB_C_brd_V02_OCP.brd")
		(comment 1 "Grand Teton / footprints 818-825 of 8354")
	)
	(layers
		(0 "F.Cu" signal "TOP")
		(4 "In1.Cu" signal "GND")
		(6 "In2.Cu" signal "IN1")
		(8 "In3.Cu" signal "GND1")
		(10 "In4.Cu" signal "IN2")
		(12 "In5.Cu" signal "GND2")
		(14 "In6.Cu" signal "IN3")
		(16 "In7.Cu" signal "GND3")
		(18 "In8.Cu" signal "VCC")
		(20 "In9.Cu" signal "VCC1")
		(22 "In10.Cu" signal "GND4")
		(24 "In11.Cu" signal "IN4")
		(26 "In12.Cu" signal "GND5")
		(28 "In13.Cu" signal "IN5")
		(30 "In14.Cu" signal "GND6")
		(32 "In15.Cu" signal "IN6")
		(34 "In16.Cu" signal "GND7")
		(2 "B.Cu" signal "BOTTOM")
		(9 "F.Adhes" user "F.Adhesive")
		(11 "B.Adhes" user "B.Adhesive")
		(13 "F.Paste" user "Package Geometry/Pastemask Top")
		(15 "B.Paste" user "Package Geometry/Pastemask Bottom")
		(5 "F.SilkS" user "Ref Des/Silkscreen Top")
		(7 "B.SilkS" user "Ref Des/Silkscreen Bottom")
		(1 "F.Mask" user "Board Geometry/Soldermask Top")
		(3 "B.Mask" user "Board Geometry/Soldermask Bottom")
		(17 "Dwgs.User" user "User.Drawings")
		(19 "Cmts.User" user "User.Comments")
		(21 "Eco1.User" user "User.Eco1")
		(23 "Eco2.User" user "User.Eco2")
		(25 "Edge.Cuts" user "Board Geometry/Outline")
		(27 "Margin" user)
		(31 "F.CrtYd" user "Package Geometry/Place Bound Top")
		(29 "B.CrtYd" user "Package Geometry/Place Bound Bottom")
		(35 "F.Fab" user "Ref Des/Assembly Top")
		(33 "B.Fab" user "Ref Des/Assembly Bottom")
	)
	(footprint ""
		(layer "F.Cu")
		(at 458.80147 -41.105836)
		(property "Reference" "Q124"
			(at -2.899664 -2.731262 0)
			(unlocked yes)
			(layer "F.SilkS")
			(effects
				(font
					(size 0.7874 0.5842)
					(thickness 0.1524)
				)
				(justify left)
			)
		)
		(property "Value" ""
			(at 0 0 0)
			(layer "F.Fab")
			(effects
				(font
					(size 1.27 1.27)
				)
			)
		)
		(duplicate_pad_numbers_are_jumpers no)
		(fp_line
			(start -1.332738 -1.100074)
			(end -0.4826 -1.100074)
			(stroke
				(width 0.1524)
				(type default)
			)
			(layer "F.SilkS")
		)
		(fp_line
			(start -1.332738 1.100074)
			(end -1.332738 -1.100074)
			(stroke
				(width 0.1524)
				(type default)
			)
			(layer "F.SilkS")
		)
		(fp_line
			(start -0.4826 -1.100074)
			(end 0 -0.541274)
			(stroke
				(width 0.1524)
				(type default)
			)
			(layer "F.SilkS")
		)
		(fp_line
			(start 0 -0.541274)
			(end 0.4826 -1.100074)
			(stroke
				(width 0.1524)
				(type default)
			)
			(layer "F.SilkS")
		)
		(fp_line
			(start 0.4826 -1.100074)
			(end 1.332738 -1.100074)
			(stroke
				(width 0.1524)
				(type default)
			)
			(layer "F.SilkS")
		)
		(fp_line
			(start 1.332738 -1.100074)
			(end 1.332738 1.100074)
			(stroke
				(width 0.1524)
				(type default)
			)
			(layer "F.SilkS")
		)
		(fp_line
			(start 1.332738 1.100074)
			(end -1.332738 1.100074)
			(stroke
				(width 0.1524)
				(type default)
			)
			(layer "F.SilkS")
		)
		(fp_poly
			(pts
				(xy -1.489456 -1.189482) (xy -2.23393 -1.43764) (xy -1.737614 -1.933956)
			)
			(stroke
				(width 0)
				(type default)
			)
			(fill yes)
			(layer "F.SilkS")
		)
		(fp_line
			(start -0.674878 -1.100074)
			(end 0.674878 -1.100074)
			(stroke
				(width 0.1)
				(type default)
			)
			(layer "F.Fab")
		)
		(fp_line
			(start -0.674878 1.100074)
			(end -0.674878 -1.100074)
			(stroke
				(width 0.1)
				(type default)
			)
			(layer "F.Fab")
		)
		(fp_line
			(start 0.674878 -1.100074)
			(end 0.674878 1.100074)
			(stroke
				(width 0.1)
				(type default)
			)
			(layer "F.Fab")
		)
		(fp_line
			(start 0.674878 1.100074)
			(end -0.674878 1.100074)
			(stroke
				(width 0.1)
				(type default)
			)
			(layer "F.Fab")
		)
		(fp_poly
			(pts
				(xy -2.2352 -0.298958) (xy -2.2352 -1.001014) (xy -1.533144 -0.649986)
			)
			(stroke
				(width 0)
				(type default)
			)
			(fill yes)
			(layer "F.Fab")
		)
		(pad "1" smd rect
			(at -0.94996 -0.649986 90)
			(size 0.4318 0.508)
			(layers "F.Cu" "F.Mask" "F.Paste")
			(net "GND")
		)
		(pad "2" smd rect
			(at -0.94996 0 90)
			(size 0.4318 0.508)
			(layers "F.Cu" "F.Mask" "F.Paste")
			(net "P3V3_OCP_EN_1_R")
		)
		(pad "3" smd rect
			(at -0.94996 0.649986 90)
			(size 0.4318 0.508)
			(layers "F.Cu" "F.Mask" "F.Paste")
			(net "P3V3_OCP_UV_1_R1")
		)
		(pad "4" smd rect
			(at 0.94996 0.649986 90)
			(size 0.4318 0.508)
			(layers "F.Cu" "F.Mask" "F.Paste")
			(net "GND")
		)
		(pad "5" smd rect
			(at 0.94996 0 90)
			(size 0.4318 0.508)
			(layers "F.Cu" "F.Mask" "F.Paste")
			(net "P3V3_OCP_1_EN_G")
		)
		(pad "6" smd rect
			(at 0.94996 -0.649986 90)
			(size 0.4318 0.508)
			(layers "F.Cu" "F.Mask" "F.Paste")
			(net "P3V3_OCP_1_EN_G")
		)
	)
	(footprint ""
		(layer "F.Cu")
		(at 432.729894 -355.743764 90)
		(property "Reference" "PR136"
			(at 0 0 90)
			(layer "F.SilkS")
			(hide yes)
			(effects
				(font
					(size 1.27 1.27)
				)
			)
		)
		(property "Value" ""
			(at 0 0 90)
			(layer "F.Fab")
			(effects
				(font
					(size 1.27 1.27)
				)
			)
		)
		(duplicate_pad_numbers_are_jumpers no)
		(fp_line
			(start 0.7874 -0.4064)
			(end 0.7874 0.4064)
			(stroke
				(width 0.1524)
				(type default)
			)
			(layer "F.SilkS")
		)
		(fp_line
			(start -0.7874 -0.4064)
			(end 0.7874 -0.4064)
			(stroke
				(width 0.1524)
				(type default)
			)
			(layer "F.SilkS")
		)
		(fp_line
			(start 0.7874 0.4064)
			(end -0.7874 0.4064)
			(stroke
				(width 0.1524)
				(type default)
			)
			(layer "F.SilkS")
		)
		(fp_line
			(start -0.7874 0.4064)
			(end -0.7874 -0.4064)
			(stroke
				(width 0.1524)
				(type default)
			)
			(layer "F.SilkS")
		)
		(fp_line
			(start -0.12065 -0.305054)
			(end -0.12065 -0.2794)
			(stroke
				(width 0.1)
				(type default)
			)
			(layer "F.Fab")
		)
		(fp_line
			(start -0.67945 -0.305054)
			(end -0.12065 -0.305054)
			(stroke
				(width 0.1)
				(type default)
			)
			(layer "F.Fab")
		)
		(fp_line
			(start 0.67945 -0.3048)
			(end 0.67945 0.3048)
			(stroke
				(width 0.1)
				(type default)
			)
			(layer "F.Fab")
		)
		(fp_line
			(start 0.12065 -0.3048)
			(end 0.67945 -0.3048)
			(stroke
				(width 0.1)
				(type default)
			)
			(layer "F.Fab")
		)
		(fp_line
			(start 0.12065 -0.2794)
			(end 0.12065 -0.3048)
			(stroke
				(width 0.1)
				(type default)
			)
			(layer "F.Fab")
		)
		(fp_line
			(start -0.12065 -0.2794)
			(end 0.12065 -0.2794)
			(stroke
				(width 0.1)
				(type default)
			)
			(layer "F.Fab")
		)
		(fp_line
			(start 0.120396 0.2794)
			(end -0.12065 0.2794)
			(stroke
				(width 0.1)
				(type default)
			)
			(layer "F.Fab")
		)
		(fp_line
			(start -0.12065 0.2794)
			(end -0.12065 0.3048)
			(stroke
				(width 0.1)
				(type default)
			)
			(layer "F.Fab")
		)
		(fp_line
			(start 0.67945 0.3048)
			(end 0.120396 0.3048)
			(stroke
				(width 0.1)
				(type default)
			)
			(layer "F.Fab")
		)
		(fp_line
			(start 0.120396 0.3048)
			(end 0.120396 0.2794)
			(stroke
				(width 0.1)
				(type default)
			)
			(layer "F.Fab")
		)
		(fp_line
			(start -0.12065 0.3048)
			(end -0.67945 0.3048)
			(stroke
				(width 0.1)
				(type default)
			)
			(layer "F.Fab")
		)
		(fp_line
			(start -0.67945 0.3048)
			(end -0.67945 -0.305054)
			(stroke
				(width 0.1)
				(type default)
			)
			(layer "F.Fab")
		)
		(pad "1" smd circle
			(at -0.40005 0 90)
			(size 0 0)
			(layers "F.Cu" "F.Mask" "F.Paste")
			(net "SW_PVDD11_S3_P0_BOOT2")
		)
		(pad "2" smd circle
			(at 0.40005 0 90)
			(size 0 0)
			(layers "F.Cu" "F.Mask" "F.Paste")
			(net "SW_PVDD11_S3_P0_BOOT2_RC")
		)
	)
	(footprint ""
		(layer "F.Cu")
		(at 15.399258 -427.232064 180)
		(property "Reference" "R6167"
			(at 0 0 180)
			(layer "F.SilkS")
			(hide yes)
			(effects
				(font
					(size 1.27 1.27)
				)
			)
		)
		(property "Value" ""
			(at 0 0 180)
			(layer "F.Fab")
			(effects
				(font
					(size 1.27 1.27)
				)
			)
		)
		(duplicate_pad_numbers_are_jumpers no)
		(fp_line
			(start 0.7874 0.4064)
			(end -0.7874 0.4064)
			(stroke
				(width 0.1524)
				(type default)
			)
			(layer "F.SilkS")
		)
		(fp_line
			(start 0.7874 -0.4064)
			(end 0.7874 0.4064)
			(stroke
				(width 0.1524)
				(type default)
			)
			(layer "F.SilkS")
		)
		(fp_line
			(start -0.7874 0.4064)
			(end -0.7874 -0.4064)
			(stroke
				(width 0.1524)
				(type default)
			)
			(layer "F.SilkS")
		)
		(fp_line
			(start -0.7874 -0.4064)
			(end 0.7874 -0.4064)
			(stroke
				(width 0.1524)
				(type default)
			)
			(layer "F.SilkS")
		)
		(fp_line
			(start 0.67945 0.3048)
			(end 0.120396 0.3048)
			(stroke
				(width 0.1)
				(type default)
			)
			(layer "F.Fab")
		)
		(fp_line
			(start 0.67945 -0.3048)
			(end 0.67945 0.3048)
			(stroke
				(width 0.1)
				(type default)
			)
			(layer "F.Fab")
		)
		(fp_line
			(start 0.12065 -0.2794)
			(end 0.12065 -0.3048)
			(stroke
				(width 0.1)
				(type default)
			)
			(layer "F.Fab")
		)
		(fp_line
			(start 0.12065 -0.3048)
			(end 0.67945 -0.3048)
			(stroke
				(width 0.1)
				(type default)
			)
			(layer "F.Fab")
		)
		(fp_line
			(start 0.120396 0.3048)
			(end 0.120396 0.2794)
			(stroke
				(width 0.1)
				(type default)
			)
			(layer "F.Fab")
		)
		(fp_line
			(start 0.120396 0.2794)
			(end -0.12065 0.2794)
			(stroke
				(width 0.1)
				(type default)
			)
			(layer "F.Fab")
		)
		(fp_line
			(start -0.12065 0.3048)
			(end -0.67945 0.3048)
			(stroke
				(width 0.1)
				(type default)
			)
			(layer "F.Fab")
		)
		(fp_line
			(start -0.12065 0.2794)
			(end -0.12065 0.3048)
			(stroke
				(width 0.1)
				(type default)
			)
			(layer "F.Fab")
		)
		(fp_line
			(start -0.12065 -0.2794)
			(end 0.12065 -0.2794)
			(stroke
				(width 0.1)
				(type default)
			)
			(layer "F.Fab")
		)
		(fp_line
			(start -0.12065 -0.305054)
			(end -0.12065 -0.2794)
			(stroke
				(width 0.1)
				(type default)
			)
			(layer "F.Fab")
		)
		(fp_line
			(start -0.67945 0.3048)
			(end -0.67945 -0.305054)
			(stroke
				(width 0.1)
				(type default)
			)
			(layer "F.Fab")
		)
		(fp_line
			(start -0.67945 -0.305054)
			(end -0.12065 -0.305054)
			(stroke
				(width 0.1)
				(type default)
			)
			(layer "F.Fab")
		)
		(pad "1" smd circle
			(at -0.40005 0 180)
			(size 0 0)
			(layers "F.Cu" "F.Mask" "F.Paste")
			(net "P3V3_AUX")
		)
		(pad "2" smd circle
			(at 0.40005 0 180)
			(size 0 0)
			(layers "F.Cu" "F.Mask" "F.Paste")
			(net "FM_P2E_BUF2_VODB_DB")
		)
	)
	(footprint ""
		(layer "F.Cu")
		(at 163.17087 -428.23638 180)
		(property "Reference" "R6790"
			(at 0 0 180)
			(layer "F.SilkS")
			(hide yes)
			(effects
				(font
					(size 1.27 1.27)
				)
			)
		)
		(property "Value" ""
			(at 0 0 180)
			(layer "F.Fab")
			(effects
				(font
					(size 1.27 1.27)
				)
			)
		)
		(duplicate_pad_numbers_are_jumpers no)
		(fp_line
			(start 0.32512 0.175006)
			(end -0.32512 0.175006)
			(stroke
				(width 0.1)
				(type default)
			)
			(layer "F.Fab")
		)
		(fp_line
			(start 0.32512 -0.175006)
			(end 0.32512 0.175006)
			(stroke
				(width 0.1)
				(type default)
			)
			(layer "F.Fab")
		)
		(fp_line
			(start -0.32512 0.175006)
			(end -0.32512 -0.175006)
			(stroke
				(width 0.1)
				(type default)
			)
			(layer "F.Fab")
		)
		(fp_line
			(start -0.32512 -0.175006)
			(end 0.32512 -0.175006)
			(stroke
				(width 0.1)
				(type default)
			)
			(layer "F.Fab")
		)
		(pad "1" smd rect
			(at -0.2667 0 180)
			(size 0.3048 0.381)
			(layers "F.Cu" "F.Mask" "F.Paste")
			(net "U20_E2")
		)
		(pad "2" smd rect
			(at 0.2667 0)
			(size 0.3048 0.381)
			(layers "F.Cu" "F.Mask" "F.Paste")
			(net "GND")
		)
	)
	(footprint ""
		(layer "F.Cu")
		(at 118.999 -124.841 -90)
		(property "Reference" "C6500"
			(at 0 0 270)
			(layer "F.SilkS")
			(hide yes)
			(effects
				(font
					(size 1.27 1.27)
				)
			)
		)
		(property "Value" ""
			(at 0 0 270)
			(layer "F.Fab")
			(effects
				(font
					(size 1.27 1.27)
				)
			)
		)
		(duplicate_pad_numbers_are_jumpers no)
		(fp_line
			(start -0.7874 0.4064)
			(end -0.7874 -0.4064)
			(stroke
				(width 0.1524)
				(type default)
			)
			(layer "F.SilkS")
		)
		(fp_line
			(start 0.7874 0.4064)
			(end -0.7874 0.4064)
			(stroke
				(width 0.1524)
				(type default)
			)
			(layer "F.SilkS")
		)
		(fp_line
			(start -0.7874 -0.4064)
			(end 0.7874 -0.4064)
			(stroke
				(width 0.1524)
				(type default)
			)
			(layer "F.SilkS")
		)
		(fp_line
			(start 0.7874 -0.4064)
			(end 0.7874 0.4064)
			(stroke
				(width 0.1524)
				(type default)
			)
			(layer "F.SilkS")
		)
		(fp_line
			(start -0.67945 0.3048)
			(end -0.67945 -0.305054)
			(stroke
				(width 0.1)
				(type default)
			)
			(layer "F.Fab")
		)
		(fp_line
			(start -0.12065 0.3048)
			(end -0.67945 0.3048)
			(stroke
				(width 0.1)
				(type default)
			)
			(layer "F.Fab")
		)
		(fp_line
			(start 0.120396 0.3048)
			(end 0.120396 0.2794)
			(stroke
				(width 0.1)
				(type default)
			)
			(layer "F.Fab")
		)
		(fp_line
			(start 0.67945 0.3048)
			(end 0.120396 0.3048)
			(stroke
				(width 0.1)
				(type default)
			)
			(layer "F.Fab")
		)
		(fp_line
			(start -0.12065 0.2794)
			(end -0.12065 0.3048)
			(stroke
				(width 0.1)
				(type default)
			)
			(layer "F.Fab")
		)
		(fp_line
			(start 0.120396 0.2794)
			(end -0.12065 0.2794)
			(stroke
				(width 0.1)
				(type default)
			)
			(layer "F.Fab")
		)
		(fp_line
			(start -0.12065 -0.2794)
			(end 0.12065 -0.2794)
			(stroke
				(width 0.1)
				(type default)
			)
			(layer "F.Fab")
		)
		(fp_line
			(start 0.12065 -0.2794)
			(end 0.12065 -0.3048)
			(stroke
				(width 0.1)
				(type default)
			)
			(layer "F.Fab")
		)
		(fp_line
			(start 0.12065 -0.3048)
			(end 0.67945 -0.3048)
			(stroke
				(width 0.1)
				(type default)
			)
			(layer "F.Fab")
		)
		(fp_line
			(start 0.67945 -0.3048)
			(end 0.67945 0.3048)
			(stroke
				(width 0.1)
				(type default)
			)
			(layer "F.Fab")
		)
		(fp_line
			(start -0.67945 -0.305054)
			(end -0.12065 -0.305054)
			(stroke
				(width 0.1)
				(type default)
			)
			(layer "F.Fab")
		)
		(fp_line
			(start -0.12065 -0.305054)
			(end -0.12065 -0.2794)
			(stroke
				(width 0.1)
				(type default)
			)
			(layer "F.Fab")
		)
		(pad "1" smd circle
			(at -0.40005 0 270)
			(size 0 0)
			(layers "F.Cu" "F.Mask" "F.Paste")
			(net "P3V3")
		)
		(pad "2" smd circle
			(at 0.40005 0 270)
			(size 0 0)
			(layers "F.Cu" "F.Mask" "F.Paste")
			(net "GND")
		)
	)
	(footprint ""
		(layer "F.Cu")
		(at 432.308 -406.7048)
		(property "Reference" "R1478"
			(at 0 0 0)
			(layer "F.SilkS")
			(hide yes)
			(effects
				(font
					(size 1.27 1.27)
				)
			)
		)
		(property "Value" ""
			(at 0 0 0)
			(layer "F.Fab")
			(effects
				(font
					(size 1.27 1.27)
				)
			)
		)
		(duplicate_pad_numbers_are_jumpers no)
		(fp_line
			(start -0.32512 -0.175006)
			(end 0.32512 -0.175006)
			(stroke
				(width 0.1)
				(type default)
			)
			(layer "F.Fab")
		)
		(fp_line
			(start -0.32512 0.175006)
			(end -0.32512 -0.175006)
			(stroke
				(width 0.1)
				(type default)
			)
			(layer "F.Fab")
		)
		(fp_line
			(start 0.32512 -0.175006)
			(end 0.32512 0.175006)
			(stroke
				(width 0.1)
				(type default)
			)
			(layer "F.Fab")
		)
		(fp_line
			(start 0.32512 0.175006)
			(end -0.32512 0.175006)
			(stroke
				(width 0.1)
				(type default)
			)
			(layer "F.Fab")
		)
		(pad "1" smd rect
			(at -0.2667 0)
			(size 0.3048 0.381)
			(layers "F.Cu" "F.Mask" "F.Paste")
			(net "P1V8_CPU0_RT_1D")
		)
		(pad "2" smd rect
			(at 0.2667 0 180)
			(size 0.3048 0.381)
			(layers "F.Cu" "F.Mask" "F.Paste")
			(net "JTAG_TDO_RT_CPU0_P2")
		)
	)
	(footprint ""
		(layer "F.Cu")
		(at 404.361904 -163.942014 90)
		(property "Reference" "PC594"
			(at 0 0 90)
			(layer "F.SilkS")
			(hide yes)
			(effects
				(font
					(size 1.27 1.27)
				)
			)
		)
		(property "Value" ""
			(at 0 0 90)
			(layer "F.Fab")
			(effects
				(font
					(size 1.27 1.27)
				)
			)
		)
		(duplicate_pad_numbers_are_jumpers no)
		(fp_line
			(start 0.7874 -0.4064)
			(end 0.7874 0.4064)
			(stroke
				(width 0.1524)
				(type default)
			)
			(layer "F.SilkS")
		)
		(fp_line
			(start -0.7874 -0.4064)
			(end 0.7874 -0.4064)
			(stroke
				(width 0.1524)
				(type default)
			)
			(layer "F.SilkS")
		)
		(fp_line
			(start 0.7874 0.4064)
			(end -0.7874 0.4064)
			(stroke
				(width 0.1524)
				(type default)
			)
			(layer "F.SilkS")
		)
		(fp_line
			(start -0.7874 0.4064)
			(end -0.7874 -0.4064)
			(stroke
				(width 0.1524)
				(type default)
			)
			(layer "F.SilkS")
		)
		(fp_line
			(start -0.12065 -0.305054)
			(end -0.12065 -0.2794)
			(stroke
				(width 0.1)
				(type default)
			)
			(layer "F.Fab")
		)
		(fp_line
			(start -0.67945 -0.305054)
			(end -0.12065 -0.305054)
			(stroke
				(width 0.1)
				(type default)
			)
			(layer "F.Fab")
		)
		(fp_line
			(start 0.67945 -0.3048)
			(end 0.67945 0.3048)
			(stroke
				(width 0.1)
				(type default)
			)
			(layer "F.Fab")
		)
		(fp_line
			(start 0.12065 -0.3048)
			(end 0.67945 -0.3048)
			(stroke
				(width 0.1)
				(type default)
			)
			(layer "F.Fab")
		)
		(fp_line
			(start 0.12065 -0.2794)
			(end 0.12065 -0.3048)
			(stroke
				(width 0.1)
				(type default)
			)
			(layer "F.Fab")
		)
		(fp_line
			(start -0.12065 -0.2794)
			(end 0.12065 -0.2794)
			(stroke
				(width 0.1)
				(type default)
			)
			(layer "F.Fab")
		)
		(fp_line
			(start 0.120396 0.2794)
			(end -0.12065 0.2794)
			(stroke
				(width 0.1)
				(type default)
			)
			(layer "F.Fab")
		)
		(fp_line
			(start -0.12065 0.2794)
			(end -0.12065 0.3048)
			(stroke
				(width 0.1)
				(type default)
			)
			(layer "F.Fab")
		)
		(fp_line
			(start 0.67945 0.3048)
			(end 0.120396 0.3048)
			(stroke
				(width 0.1)
				(type default)
			)
			(layer "F.Fab")
		)
		(fp_line
			(start 0.120396 0.3048)
			(end 0.120396 0.2794)
			(stroke
				(width 0.1)
				(type default)
			)
			(layer "F.Fab")
		)
		(fp_line
			(start -0.12065 0.3048)
			(end -0.67945 0.3048)
			(stroke
				(width 0.1)
				(type default)
			)
			(layer "F.Fab")
		)
		(fp_line
			(start -0.67945 0.3048)
			(end -0.67945 -0.305054)
			(stroke
				(width 0.1)
				(type default)
			)
			(layer "F.Fab")
		)
		(pad "1" smd circle
			(at -0.40005 0 90)
			(size 0 0)
			(layers "F.Cu" "F.Mask" "F.Paste")
			(net "SW_PVDDCR_SOC_P0_BOOT2_RC")
		)
		(pad "2" smd circle
			(at 0.40005 0 90)
			(size 0 0)
			(layers "F.Cu" "F.Mask" "F.Paste")
			(net "SW_PVDDCR_SOC_P0_PH2")
		)
	)
	(footprint ""
		(layer "F.Cu")
		(at 180.528468 -44.091098)
		(property "Reference" "C9104"
			(at 0 0 0)
			(layer "F.SilkS")
			(hide yes)
			(effects
				(font
					(size 1.27 1.27)
				)
			)
		)
		(property "Value" ""
			(at 0 0 0)
			(layer "F.Fab")
			(effects
				(font
					(size 1.27 1.27)
				)
			)
		)
		(duplicate_pad_numbers_are_jumpers no)
		(fp_line
			(start -0.299974 -0.150114)
			(end 0.299974 -0.150114)
			(stroke
				(width 0.1)
				(type default)
			)
			(layer "F.Fab")
		)
		(fp_line
			(start -0.299974 0.150114)
			(end -0.299974 -0.150114)
			(stroke
				(width 0.1)
				(type default)
			)
			(layer "F.Fab")
		)
		(fp_line
			(start 0.299974 -0.150114)
			(end 0.299974 0.150114)
			(stroke
				(width 0.1)
				(type default)
			)
			(layer "F.Fab")
		)
		(fp_line
			(start 0.299974 0.150114)
			(end -0.299974 0.150114)
			(stroke
				(width 0.1)
				(type default)
			)
			(layer "F.Fab")
		)
		(pad "1" smd rect
			(at -0.2667 0)
			(size 0.3048 0.381)
			(layers "F.Cu" "F.Mask" "F.Paste")
			(net "P3E_CPU1_P4_TX_C_DP<0>")
		)
		(pad "2" smd rect
			(at 0.2667 0)
			(size 0.3048 0.381)
			(layers "F.Cu" "F.Mask" "F.Paste")
			(net "P3E_CPU1_P4_TX_DP<0>")
		)
	)
)
